# T6G (Grand Teton) — schematic netlist excerpt (pin names and nets, part order shuffled) for the footprints in the layout excerpt that follows; sources: Cadence DE-HDL packaged netlist, KiCad conversion of 04192023_DAF0TMB3IC0_F0TG_MB_C_brd_V02_OCP.brd

PC6558_1  Q_CAP  22UF 16V 20% X6S  pkg C0805  page 363 : A = SW_P12V_AUX_P0V9_RETIMER_CPU0_FLT ; B = GND
C60  Q_CAP  10UF 16V 10% EMPTY  pkg C0805  page 188 : A = P3V3_AUX ; B = GND

(kicad_pcb
	(version 20260206)
	(generator "pcbnew")
	(generator_version "10.0")
	(general
		(thickness 1.6)
		(legacy_teardrops no)
	)
	(paper "A4")
	(title_block
		(title "04192023_DAF0TMB3IC0_F0TG_MB_C_brd_V02_OCP.brd")
		(comment 1 "Grand Teton / footprints 1116-1117 of 8354")
	)
	(layers
		(0 "F.Cu" signal "TOP")
		(4 "In1.Cu" signal "GND")
		(6 "In2.Cu" signal "IN1")
		(8 "In3.Cu" signal "GND1")
		(10 "In4.Cu" signal "IN2")
		(12 "In5.Cu" signal "GND2")
		(14 "In6.Cu" signal "IN3")
		(16 "In7.Cu" signal "GND3")
		(18 "In8.Cu" signal "VCC")
		(20 "In9.Cu" signal "VCC1")
		(22 "In10.Cu" signal "GND4")
		(24 "In11.Cu" signal "IN4")
		(26 "In12.Cu" signal "GND5")
		(28 "In13.Cu" signal "IN5")
		(30 "In14.Cu" signal "GND6")
		(32 "In15.Cu" signal "IN6")
		(34 "In16.Cu" signal "GND7")
		(2 "B.Cu" signal "BOTTOM")
		(9 "F.Adhes" user "F.Adhesive")
		(11 "B.Adhes" user "B.Adhesive")
		(13 "F.Paste" user "Package Geometry/Pastemask Top")
		(15 "B.Paste" user "Package Geometry/Pastemask Bottom")
		(5 "F.SilkS" user "Ref Des/Silkscreen Top")
		(7 "B.SilkS" user "Ref Des/Silkscreen Bottom")
		(1 "F.Mask" user "Board Geometry/Soldermask Top")
		(3 "B.Mask" user "Board Geometry/Soldermask Bottom")
		(17 "Dwgs.User" user "User.Drawings")
		(19 "Cmts.User" user "User.Comments")
		(21 "Eco1.User" user "User.Eco1")
		(23 "Eco2.User" user "User.Eco2")
		(25 "Edge.Cuts" user "Board Geometry/Outline")
		(27 "Margin" user)
		(31 "F.CrtYd" user "Package Geometry/Place Bound Top")
		(29 "B.CrtYd" user "Package Geometry/Place Bound Bottom")
		(35 "F.Fab" user "Ref Des/Assembly Top")
		(33 "B.Fab" user "Ref Des/Assembly Bottom")
	)
	(footprint ""
		(layer "F.Cu")
		(at 447.237866 -405.7777 180)
		(property "Reference" "PC6558_1"
			(at 0 0 180)
			(layer "F.SilkS")
			(hide yes)
			(effects
				(font
					(size 1.27 1.27)
				)
			)
		)
		(property "Value" ""
			(at 0 0 180)
			(layer "F.Fab")
			(effects
				(font
					(size 1.27 1.27)
				)
			)
		)
		(duplicate_pad_numbers_are_jumpers no)
		(fp_line
			(start 1.524 0.762)
			(end -1.524 0.762)
			(stroke
				(width 0.1524)
				(type default)
			)
			(layer "F.SilkS")
		)
		(fp_line
			(start 1.524 -0.762)
			(end 1.524 0.762)
			(stroke
				(width 0.1524)
				(type default)
			)
			(layer "F.SilkS")
		)
		(fp_line
			(start -1.524 0.762)
			(end -1.524 -0.762)
			(stroke
				(width 0.1524)
				(type default)
			)
			(layer "F.SilkS")
		)
		(fp_line
			(start -1.524 -0.762)
			(end 1.524 -0.762)
			(stroke
				(width 0.1524)
				(type default)
			)
			(layer "F.SilkS")
		)
		(fp_line
			(start 1.1049 0.724916)
			(end 1.1049 -0.724916)
			(stroke
				(width 0.1)
				(type default)
			)
			(layer "F.Fab")
		)
		(fp_line
			(start 1.1049 -0.724916)
			(end -1.1049 -0.724916)
			(stroke
				(width 0.1)
				(type default)
			)
			(layer "F.Fab")
		)
		(fp_line
			(start -1.1049 0.724916)
			(end 1.1049 0.724916)
			(stroke
				(width 0.1)
				(type default)
			)
			(layer "F.Fab")
		)
		(fp_line
			(start -1.1049 -0.724916)
			(end -1.1049 0.724916)
			(stroke
				(width 0.1)
				(type default)
			)
			(layer "F.Fab")
		)
		(pad "1" smd rect
			(at -0.889 0)
			(size 1.016 1.27)
			(layers "F.Cu" "F.Mask" "F.Paste")
			(net "SW_P12V_AUX_P0V9_RETIMER_CPU0_FLT")
		)
		(pad "2" smd rect
			(at 0.889 0)
			(size 1.016 1.27)
			(layers "F.Cu" "F.Mask" "F.Paste")
			(net "GND")
		)
	)
	(footprint ""
		(layer "F.Cu")
		(at 446.52438 -65.767458 -90)
		(property "Reference" "C60"
			(at 0 0 270)
			(layer "F.SilkS")
			(hide yes)
			(effects
				(font
					(size 1.27 1.27)
				)
			)
		)
		(property "Value" ""
			(at 0 0 270)
			(layer "F.Fab")
			(effects
				(font
					(size 1.27 1.27)
				)
			)
		)
		(duplicate_pad_numbers_are_jumpers no)
		(fp_line
			(start -1.524 0.762)
			(end -1.524 -0.762)
			(stroke
				(width 0.1524)
				(type default)
			)
			(layer "F.SilkS")
		)
		(fp_line
			(start 1.524 0.762)
			(end -1.524 0.762)
			(stroke
				(width 0.1524)
				(type default)
			)
			(layer "F.SilkS")
		)
		(fp_line
			(start -1.524 -0.762)
			(end 1.524 -0.762)
			(stroke
				(width 0.1524)
				(type default)
			)
			(layer "F.SilkS")
		)
		(fp_line
			(start 1.524 -0.762)
			(end 1.524 0.762)
			(stroke
				(width 0.1524)
				(type default)
			)
			(layer "F.SilkS")
		)
		(fp_line
			(start -1.1049 0.724916)
			(end 1.1049 0.724916)
			(stroke
				(width 0.1)
				(type default)
			)
			(layer "F.Fab")
		)
		(fp_line
			(start 1.1049 0.724916)
			(end 1.1049 -0.724916)
			(stroke
				(width 0.1)
				(type default)
			)
			(layer "F.Fab")
		)
		(fp_line
			(start -1.1049 -0.724916)
			(end -1.1049 0.724916)
			(stroke
				(width 0.1)
				(type default)
			)
			(layer "F.Fab")
		)
		(fp_line
			(start 1.1049 -0.724916)
			(end -1.1049 -0.724916)
			(stroke
				(width 0.1)
				(type default)
			)
			(layer "F.Fab")
		)
		(pad "1" smd rect
			(at -0.889 0 90)
			(size 1.016 1.27)
			(layers "F.Cu" "F.Mask" "F.Paste")
			(net "P3V3_AUX")
		)
		(pad "2" smd rect
			(at 0.889 0 90)
			(size 1.016 1.27)
			(layers "F.Cu" "F.Mask" "F.Paste")
			(net "GND")
		)
	)
)
